(kicad_pcb
	(version 20260206)
	(generator "pcbnew")
	(generator_version "10.0")
	(general
		(thickness 1.6)
		(legacy_teardrops no)
	)
	(paper "A4")
	(title_block
		(title "m-2 — Lightning_M.2_BRD.brd")
		(comment 1 "Lightning (Wiwynn / Facebook NVMe JBOF) / footprints 115-123 of 157")
	)
	(layers
		(0 "F.Cu" signal "TOP")
		(4 "In1.Cu" signal "L2GND")
		(6 "In2.Cu" signal "L3")
		(8 "In3.Cu" signal "L4GND")
		(10 "In4.Cu" signal "L5GND")
		(12 "In5.Cu" signal "L6")
		(14 "In6.Cu" signal "L7GND")
		(2 "B.Cu" signal "BOTTOM")
		(9 "F.Adhes" user "F.Adhesive")
		(11 "B.Adhes" user "B.Adhesive")
		(13 "F.Paste" user "Package Geometry/Pastemask Top")
		(15 "B.Paste" user "Package Geometry/Pastemask Bottom")
		(5 "F.SilkS" user "Ref Des/Silkscreen Top")
		(7 "B.SilkS" user "Ref Des/Silkscreen Bottom")
		(1 "F.Mask" user "Board Geometry/Soldermask Top")
		(3 "B.Mask" user "Board Geometry/Soldermask Bottom")
		(17 "Dwgs.User" user "User.Drawings")
		(19 "Cmts.User" user "User.Comments")
		(21 "Eco1.User" user "User.Eco1")
		(23 "Eco2.User" user "User.Eco2")
		(25 "Edge.Cuts" user "Board Geometry/Outline")
		(27 "Margin" user)
		(31 "F.CrtYd" user "Package Geometry/Place Bound Top")
		(29 "B.CrtYd" user "Package Geometry/Place Bound Bottom")
		(35 "F.Fab" user "Ref Des/Assembly Top")
		(33 "B.Fab" user "Ref Des/Assembly Bottom")
	)
	(footprint ""
		(layer "B.Cu")
		(at 56.466994 -77.724)
		(property "Reference" "PC41"
			(at 0 0 0)
			(layer "B.SilkS")
			(hide yes)
			(effects
				(font
					(size 1.27 1.27)
				)
				(justify mirror)
			)
		)
		(property "Value" "SCD1U25V2KX-2-GP"
			(at -1.1811 -2.7051 0)
			(unlocked yes)
			(layer "B.Fab")
			(hide yes)
			(effects
				(font
					(size 1.016 1.016)
					(thickness 0.1524)
				)
				(justify mirror)
			)
		)
		(property "Device Type" "C402H22"
			(at -1.1811 -4.2291 0)
			(unlocked yes)
			(layer "B.Fab")
			(hide yes)
			(effects
				(font
					(size 1.016 1.016)
					(thickness 0.1524)
				)
				(justify mirror)
			)
		)
		(duplicate_pad_numbers_are_jumpers no)
		(fp_rect
			(start 0.4318 0.9525)
			(end -0.4318 -0.9525)
			(stroke
				(width 0)
				(type default)
			)
			(fill no)
			(layer "B.CrtYd")
		)
		(fp_rect
			(start 0.4318 0.9525)
			(end -0.4318 -0.9525)
			(stroke
				(width 0)
				(type default)
			)
			(fill no)
			(layer "B.Fab")
		)
		(pad "1" smd custom
			(at 0 -0.4445 180)
			(size 0.1524 0.1524)
			(layers "B.Cu" "B.Mask" "B.Paste")
			(net "P3V3_PWR")
			(options
				(clearance outline)
				(anchor circle)
			)
			(primitives
				(gr_poly
					(pts
						(arc
							(start 0.3048 0.2032)
							(mid 0.275042 0.275042)
							(end 0.2032 0.3048)
						)
						(arc
							(start -0.2032 0.3048)
							(mid -0.275042 0.275042)
							(end -0.3048 0.2032)
						)
						(arc
							(start -0.3048 -0.2032)
							(mid -0.275042 -0.275042)
							(end -0.2032 -0.3048)
						)
						(arc
							(start 0.2032 -0.3048)
							(mid 0.275042 -0.275042)
							(end 0.3048 -0.2032)
						)
					)
					(width 0)
					(fill yes)
				)
			)
		)
		(pad "2" smd custom
			(at 0 0.4445 180)
			(size 0.1524 0.1524)
			(layers "B.Cu" "B.Mask" "B.Paste")
			(net "P3V3_DEV_LL_R")
			(options
				(clearance outline)
				(anchor circle)
			)
			(primitives
				(gr_poly
					(pts
						(arc
							(start 0.3048 0.2032)
							(mid 0.275042 0.275042)
							(end 0.2032 0.3048)
						)
						(arc
							(start -0.2032 0.3048)
							(mid -0.275042 0.275042)
							(end -0.3048 0.2032)
						)
						(arc
							(start -0.3048 -0.2032)
							(mid -0.275042 -0.275042)
							(end -0.2032 -0.3048)
						)
						(arc
							(start 0.2032 -0.3048)
							(mid 0.275042 -0.275042)
							(end 0.3048 -0.2032)
						)
					)
					(width 0)
					(fill yes)
				)
			)
		)
	)
	(footprint ""
		(layer "B.Cu")
		(at 39.575994 -78.613)
		(property "Reference" "PC36"
			(at 0 0 0)
			(layer "B.SilkS")
			(hide yes)
			(effects
				(font
					(size 1.27 1.27)
				)
				(justify mirror)
			)
		)
		(property "Value" "SC4D7U25V5KX-1-GP"
			(at 0.0762 -6.1214 0)
			(unlocked yes)
			(layer "B.Fab")
			(hide yes)
			(effects
				(font
					(size 1.016 1.016)
					(thickness 0.1524)
				)
				(justify mirror)
			)
		)
		(property "Device Type" "C805H58"
			(at 0.0762 -8.1534 0)
			(unlocked yes)
			(layer "B.Fab")
			(hide yes)
			(effects
				(font
					(size 1.016 1.016)
					(thickness 0.1524)
				)
				(justify mirror)
			)
		)
		(duplicate_pad_numbers_are_jumpers no)
		(fp_line
			(start -0.635 0)
			(end 0.635 0)
			(stroke
				(width 0.508)
				(type default)
			)
			(layer "B.SilkS")
		)
		(fp_rect
			(start 0.9652 1.778)
			(end -0.9652 -1.778)
			(stroke
				(width 0)
				(type default)
			)
			(fill no)
			(layer "B.CrtYd")
		)
		(fp_poly
			(pts
				(xy 0.9652 -1.778) (xy -0.9652 -1.778) (xy -0.9652 1.778) (xy 0.9652 1.778)
			)
			(stroke
				(width 0)
				(type default)
			)
			(fill no)
			(layer "B.Fab")
		)
		(pad "1" smd rect
			(at 0 -0.9652 180)
			(size 1.397 1.143)
			(layers "B.Cu" "B.Mask" "B.Paste")
			(net "P3V3_DEV_VDD")
		)
		(pad "2" smd rect
			(at 0 0.9652 180)
			(size 1.397 1.143)
			(layers "B.Cu" "B.Mask" "B.Paste")
			(net "GND")
		)
	)
	(footprint ""
		(layer "B.Cu")
		(at 64.008 -48.514)
		(property "Reference" "TP6"
			(at 0 0 0)
			(layer "B.SilkS")
			(hide yes)
			(effects
				(font
					(size 1.27 1.27)
				)
				(justify mirror)
			)
		)
		(property "Value" "TPAD28-1-GP-U"
			(at -0.0508 -1.9304 0)
			(unlocked yes)
			(layer "B.Fab")
			(hide yes)
			(effects
				(font
					(size 1.016 1.016)
					(thickness 0.1524)
				)
				(justify mirror)
			)
		)
		(property "Device Type" "TPAD28-1-U"
			(at -0.0508 -3.4544 0)
			(unlocked yes)
			(layer "B.Fab")
			(hide yes)
			(effects
				(font
					(size 1.016 1.016)
					(thickness 0.1524)
				)
				(justify mirror)
			)
		)
		(duplicate_pad_numbers_are_jumpers no)
		(fp_poly
			(pts
				(arc
					(start 0.3556 0)
					(mid -0.3556 0)
					(end 0.3556 0)
				)
			)
			(stroke
				(width 0)
				(type default)
			)
			(fill no)
			(layer "B.CrtYd")
		)
		(fp_poly
			(pts
				(arc
					(start 0.9525 0)
					(mid -0.9525 0)
					(end 0.9525 0)
				)
			)
			(stroke
				(width 0)
				(type default)
			)
			(fill no)
			(layer "B.Fab")
		)
		(pad "1" smd circle
			(at 0 0 180)
			(size 0.7112 0.7112)
			(layers "B.Cu" "B.Mask" "B.Paste")
			(net "SSD_A1_MFG_CLK_TP")
		)
	)
	(footprint ""
		(layer "B.Cu")
		(at 65.913 -48.514)
		(property "Reference" "TP7"
			(at 0 0 0)
			(layer "B.SilkS")
			(hide yes)
			(effects
				(font
					(size 1.27 1.27)
				)
				(justify mirror)
			)
		)
		(property "Value" "TPAD28-1-GP-U"
			(at -0.0508 -1.9304 0)
			(unlocked yes)
			(layer "B.Fab")
			(hide yes)
			(effects
				(font
					(size 1.016 1.016)
					(thickness 0.1524)
				)
				(justify mirror)
			)
		)
		(property "Device Type" "TPAD28-1-U"
			(at -0.0508 -3.4544 0)
			(unlocked yes)
			(layer "B.Fab")
			(hide yes)
			(effects
				(font
					(size 1.016 1.016)
					(thickness 0.1524)
				)
				(justify mirror)
			)
		)
		(duplicate_pad_numbers_are_jumpers no)
		(fp_poly
			(pts
				(arc
					(start 0.3556 0)
					(mid -0.3556 0)
					(end 0.3556 0)
				)
			)
			(stroke
				(width 0)
				(type default)
			)
			(fill no)
			(layer "B.CrtYd")
		)
		(fp_poly
			(pts
				(arc
					(start 0.9525 0)
					(mid -0.9525 0)
					(end 0.9525 0)
				)
			)
			(stroke
				(width 0)
				(type default)
			)
			(fill no)
			(layer "B.Fab")
		)
		(pad "1" smd circle
			(at 0 0 180)
			(size 0.7112 0.7112)
			(layers "B.Cu" "B.Mask" "B.Paste")
			(net "SSD_A1_MFG_DATA_TP")
		)
	)
	(footprint ""
		(layer "B.Cu")
		(at 65.278 -41.783 -90)
		(property "Reference" "C39"
			(at 0 0 90)
			(layer "B.SilkS")
			(hide yes)
			(effects
				(font
					(size 1.27 1.27)
				)
				(justify mirror)
			)
		)
		(property "Value" "SCD1U16V2KX-3GP"
			(at -1.1811 -2.7051 270)
			(unlocked yes)
			(layer "B.Fab")
			(hide yes)
			(effects
				(font
					(size 1.016 1.016)
					(thickness 0.1524)
				)
				(justify mirror)
			)
		)
		(property "Device Type" "C402H22"
			(at -1.1811 -4.2291 270)
			(unlocked yes)
			(layer "B.Fab")
			(hide yes)
			(effects
				(font
					(size 1.016 1.016)
					(thickness 0.1524)
				)
				(justify mirror)
			)
		)
		(duplicate_pad_numbers_are_jumpers no)
		(fp_rect
			(start 0.4318 0.9525)
			(end -0.4318 -0.9525)
			(stroke
				(width 0)
				(type default)
			)
			(fill no)
			(layer "B.CrtYd")
		)
		(fp_rect
			(start 0.4318 0.9525)
			(end -0.4318 -0.9525)
			(stroke
				(width 0)
				(type default)
			)
			(fill no)
			(layer "B.Fab")
		)
		(pad "1" smd custom
			(at 0 -0.4445 90)
			(size 0.1524 0.1524)
			(layers "B.Cu" "B.Mask" "B.Paste")
			(net "P3V3_DPB")
			(options
				(clearance outline)
				(anchor circle)
			)
			(primitives
				(gr_poly
					(pts
						(arc
							(start 0.3048 0.2032)
							(mid 0.275042 0.275042)
							(end 0.2032 0.3048)
						)
						(arc
							(start -0.2032 0.3048)
							(mid -0.275042 0.275042)
							(end -0.3048 0.2032)
						)
						(arc
							(start -0.3048 -0.2032)
							(mid -0.275042 -0.275042)
							(end -0.2032 -0.3048)
						)
						(arc
							(start 0.2032 -0.3048)
							(mid 0.275042 -0.275042)
							(end 0.3048 -0.2032)
						)
					)
					(width 0)
					(fill yes)
				)
			)
		)
		(pad "2" smd custom
			(at 0 0.4445 90)
			(size 0.1524 0.1524)
			(layers "B.Cu" "B.Mask" "B.Paste")
			(net "GND")
			(options
				(clearance outline)
				(anchor circle)
			)
			(primitives
				(gr_poly
					(pts
						(arc
							(start 0.3048 0.2032)
							(mid 0.275042 0.275042)
							(end 0.2032 0.3048)
						)
						(arc
							(start -0.2032 0.3048)
							(mid -0.275042 0.275042)
							(end -0.3048 0.2032)
						)
						(arc
							(start -0.3048 -0.2032)
							(mid -0.275042 -0.275042)
							(end -0.2032 -0.3048)
						)
						(arc
							(start 0.2032 -0.3048)
							(mid 0.275042 -0.275042)
							(end 0.3048 -0.2032)
						)
					)
					(width 0)
					(fill yes)
				)
			)
		)
	)
	(footprint ""
		(layer "B.Cu")
		(at 26.543 -77.216)
		(property "Reference" "R62"
			(at 0 0 0)
			(layer "B.SilkS")
			(hide yes)
			(effects
				(font
					(size 1.27 1.27)
				)
				(justify mirror)
			)
		)
		(property "Value" "0R2J-2-GP"
			(at -0.064008 -3.993896 0)
			(unlocked yes)
			(layer "B.Fab")
			(hide yes)
			(effects
				(font
					(size 1.016 1.016)
					(thickness 0.1524)
				)
				(justify mirror)
			)
		)
		(property "Device Type" "R402H16"
			(at -0.064008 -5.517896 0)
			(unlocked yes)
			(layer "B.Fab")
			(hide yes)
			(effects
				(font
					(size 1.016 1.016)
					(thickness 0.1524)
				)
				(justify mirror)
			)
		)
		(duplicate_pad_numbers_are_jumpers no)
		(fp_line
			(start -0.508 -0.9398)
			(end 0.508 -0.9398)
			(stroke
				(width 0.1524)
				(type default)
			)
			(layer "B.SilkS")
		)
		(fp_line
			(start 0.508 -0.9398)
			(end 0.508 0.9398)
			(stroke
				(width 0.1524)
				(type default)
			)
			(layer "B.SilkS")
		)
		(fp_rect
			(start 0.508 0.9398)
			(end -0.508 -0.9398)
			(stroke
				(width 0)
				(type default)
			)
			(fill no)
			(layer "B.CrtYd")
		)
		(fp_rect
			(start 0.508 0.9398)
			(end -0.508 -0.9398)
			(stroke
				(width 0)
				(type default)
			)
			(fill no)
			(layer "B.Fab")
		)
		(pad "1" smd custom
			(at 0 -0.4445 180)
			(size 0.1397 0.1397)
			(layers "B.Cu" "B.Mask" "B.Paste")
			(net "Z50_SSD_B1_SMB_DATA_R")
			(options
				(clearance outline)
				(anchor circle)
			)
			(primitives
				(gr_poly
					(pts
						(arc
							(start -0.1778 0.2794)
							(mid -0.249642 0.249642)
							(end -0.2794 0.1778)
						)
						(arc
							(start -0.2794 -0.1778)
							(mid -0.249642 -0.249642)
							(end -0.1778 -0.2794)
						)
						(arc
							(start 0.1778 -0.2794)
							(mid 0.249642 -0.249642)
							(end 0.2794 -0.1778)
						)
						(arc
							(start 0.2794 0.1778)
							(mid 0.249642 0.249642)
							(end 0.1778 0.2794)
						)
					)
					(width 0)
					(fill yes)
				)
			)
		)
		(pad "2" smd custom
			(at 0 0.4445 180)
			(size 0.1397 0.1397)
			(layers "B.Cu" "B.Mask" "B.Paste")
			(net "Z50_SSD_B1_SMB_DATA")
			(options
				(clearance outline)
				(anchor circle)
			)
			(primitives
				(gr_poly
					(pts
						(arc
							(start -0.1778 0.2794)
							(mid -0.249642 0.249642)
							(end -0.2794 0.1778)
						)
						(arc
							(start -0.2794 -0.1778)
							(mid -0.249642 -0.249642)
							(end -0.1778 -0.2794)
						)
						(arc
							(start 0.1778 -0.2794)
							(mid 0.249642 -0.249642)
							(end 0.2794 -0.1778)
						)
						(arc
							(start 0.2794 0.1778)
							(mid 0.249642 0.249642)
							(end 0.1778 0.2794)
						)
					)
					(width 0)
					(fill yes)
				)
			)
		)
	)
	(footprint ""
		(layer "B.Cu")
		(at 62.738 -38.735 90)
		(property "Reference" "R5"
			(at 0 0 90)
			(layer "B.SilkS")
			(hide yes)
			(effects
				(font
					(size 1.27 1.27)
				)
				(justify mirror)
			)
		)
		(property "Value" "0R2J-2-GP"
			(at -0.064008 -3.993896 90)
			(unlocked yes)
			(layer "B.Fab")
			(hide yes)
			(effects
				(font
					(size 1.016 1.016)
					(thickness 0.1524)
				)
				(justify mirror)
			)
		)
		(property "Device Type" "R402H16"
			(at -0.064008 -5.517896 90)
			(unlocked yes)
			(layer "B.Fab")
			(hide yes)
			(effects
				(font
					(size 1.016 1.016)
					(thickness 0.1524)
				)
				(justify mirror)
			)
		)
		(duplicate_pad_numbers_are_jumpers no)
		(fp_line
			(start 0.508 -0.9398)
			(end 0.508 0.9398)
			(stroke
				(width 0.1524)
				(type default)
			)
			(layer "B.SilkS")
		)
		(fp_line
			(start -0.508 -0.9398)
			(end 0.508 -0.9398)
			(stroke
				(width 0.1524)
				(type default)
			)
			(layer "B.SilkS")
		)
		(fp_rect
			(start 0.508 0.9398)
			(end -0.508 -0.9398)
			(stroke
				(width 0)
				(type default)
			)
			(fill no)
			(layer "B.CrtYd")
		)
		(fp_rect
			(start 0.508 0.9398)
			(end -0.508 -0.9398)
			(stroke
				(width 0)
				(type default)
			)
			(fill no)
			(layer "B.Fab")
		)
		(pad "1" smd custom
			(at 0 -0.4445 270)
			(size 0.1397 0.1397)
			(layers "B.Cu" "B.Mask" "B.Paste")
			(net "Z50_SMB_DATA")
			(options
				(clearance outline)
				(anchor circle)
			)
			(primitives
				(gr_poly
					(pts
						(arc
							(start -0.1778 0.2794)
							(mid -0.249642 0.249642)
							(end -0.2794 0.1778)
						)
						(arc
							(start -0.2794 -0.1778)
							(mid -0.249642 -0.249642)
							(end -0.1778 -0.2794)
						)
						(arc
							(start 0.1778 -0.2794)
							(mid 0.249642 -0.249642)
							(end 0.2794 -0.1778)
						)
						(arc
							(start 0.2794 0.1778)
							(mid 0.249642 0.249642)
							(end 0.1778 0.2794)
						)
					)
					(width 0)
					(fill yes)
				)
			)
		)
		(pad "2" smd custom
			(at 0 0.4445 270)
			(size 0.1397 0.1397)
			(layers "B.Cu" "B.Mask" "B.Paste")
			(net "Z50_TEMP_1_DATA")
			(options
				(clearance outline)
				(anchor circle)
			)
			(primitives
				(gr_poly
					(pts
						(arc
							(start -0.1778 0.2794)
							(mid -0.249642 0.249642)
							(end -0.2794 0.1778)
						)
						(arc
							(start -0.2794 -0.1778)
							(mid -0.249642 -0.249642)
							(end -0.1778 -0.2794)
						)
						(arc
							(start 0.1778 -0.2794)
							(mid 0.249642 -0.249642)
							(end 0.2794 -0.1778)
						)
						(arc
							(start 0.2794 0.1778)
							(mid 0.249642 0.249642)
							(end 0.1778 0.2794)
						)
					)
					(width 0)
					(fill yes)
				)
			)
		)
	)
	(footprint ""
		(layer "B.Cu")
		(at 25.019 -81.534 -90)
		(property "Reference" "R25"
			(at 0 0 90)
			(layer "B.SilkS")
			(hide yes)
			(effects
				(font
					(size 1.27 1.27)
				)
				(justify mirror)
			)
		)
		(property "Value" "4K7R2F-GP"
			(at -0.064008 -3.993896 270)
			(unlocked yes)
			(layer "B.Fab")
			(hide yes)
			(effects
				(font
					(size 1.016 1.016)
					(thickness 0.1524)
				)
				(justify mirror)
			)
		)
		(property "Device Type" "R402H16"
			(at -0.064008 -5.517896 270)
			(unlocked yes)
			(layer "B.Fab")
			(hide yes)
			(effects
				(font
					(size 1.016 1.016)
					(thickness 0.1524)
				)
				(justify mirror)
			)
		)
		(duplicate_pad_numbers_are_jumpers no)
		(fp_line
			(start -0.508 -0.9398)
			(end 0.508 -0.9398)
			(stroke
				(width 0.1524)
				(type default)
			)
			(layer "B.SilkS")
		)
		(fp_line
			(start 0.508 -0.9398)
			(end 0.508 0.9398)
			(stroke
				(width 0.1524)
				(type default)
			)
			(layer "B.SilkS")
		)
		(fp_rect
			(start 0.508 0.9398)
			(end -0.508 -0.9398)
			(stroke
				(width 0)
				(type default)
			)
			(fill no)
			(layer "B.CrtYd")
		)
		(fp_rect
			(start 0.508 0.9398)
			(end -0.508 -0.9398)
			(stroke
				(width 0)
				(type default)
			)
			(fill no)
			(layer "B.Fab")
		)
		(pad "1" smd custom
			(at 0 -0.4445 90)
			(size 0.1397 0.1397)
			(layers "B.Cu" "B.Mask" "B.Paste")
			(net "Z50_SMB_SWITCH_ADDRESS_A1")
			(options
				(clearance outline)
				(anchor circle)
			)
			(primitives
				(gr_poly
					(pts
						(arc
							(start -0.1778 0.2794)
							(mid -0.249642 0.249642)
							(end -0.2794 0.1778)
						)
						(arc
							(start -0.2794 -0.1778)
							(mid -0.249642 -0.249642)
							(end -0.1778 -0.2794)
						)
						(arc
							(start 0.1778 -0.2794)
							(mid 0.249642 -0.249642)
							(end 0.2794 -0.1778)
						)
						(arc
							(start 0.2794 0.1778)
							(mid 0.249642 0.249642)
							(end 0.1778 0.2794)
						)
					)
					(width 0)
					(fill yes)
				)
			)
		)
		(pad "2" smd custom
			(at 0 0.4445 90)
			(size 0.1397 0.1397)
			(layers "B.Cu" "B.Mask" "B.Paste")
			(net "GND")
			(options
				(clearance outline)
				(anchor circle)
			)
			(primitives
				(gr_poly
					(pts
						(arc
							(start -0.1778 0.2794)
							(mid -0.249642 0.249642)
							(end -0.2794 0.1778)
						)
						(arc
							(start -0.2794 -0.1778)
							(mid -0.249642 -0.249642)
							(end -0.1778 -0.2794)
						)
						(arc
							(start 0.1778 -0.2794)
							(mid 0.249642 -0.249642)
							(end 0.2794 -0.1778)
						)
						(arc
							(start 0.2794 0.1778)
							(mid 0.249642 0.249642)
							(end 0.1778 0.2794)
						)
					)
					(width 0)
					(fill yes)
				)
			)
		)
	)
	(footprint ""
		(layer "B.Cu")
		(at 65.278 -40.767 -90)
		(property "Reference" "R21"
			(at 0 0 90)
			(layer "B.SilkS")
			(hide yes)
			(effects
				(font
					(size 1.27 1.27)
				)
				(justify mirror)
			)
		)
		(property "Value" "4K7R2F-GP"
			(at -0.064008 -3.993896 270)
			(unlocked yes)
			(layer "B.Fab")
			(hide yes)
			(effects
				(font
					(size 1.016 1.016)
					(thickness 0.1524)
				)
				(justify mirror)
			)
		)
		(property "Device Type" "R402H16"
			(at -0.064008 -5.517896 270)
			(unlocked yes)
			(layer "B.Fab")
			(hide yes)
			(effects
				(font
					(size 1.016 1.016)
					(thickness 0.1524)
				)
				(justify mirror)
			)
		)
		(duplicate_pad_numbers_are_jumpers no)
		(fp_line
			(start -0.508 -0.9398)
			(end 0.508 -0.9398)
			(stroke
				(width 0.1524)
				(type default)
			)
			(layer "B.SilkS")
		)
		(fp_line
			(start 0.508 -0.9398)
			(end 0.508 0.9398)
			(stroke
				(width 0.1524)
				(type default)
			)
			(layer "B.SilkS")
		)
		(fp_rect
			(start 0.508 0.9398)
			(end -0.508 -0.9398)
			(stroke
				(width 0)
				(type default)
			)
			(fill no)
			(layer "B.CrtYd")
		)
		(fp_rect
			(start 0.508 0.9398)
			(end -0.508 -0.9398)
			(stroke
				(width 0)
				(type default)
			)
			(fill no)
			(layer "B.Fab")
		)
		(pad "1" smd custom
			(at 0 -0.4445 90)
			(size 0.1397 0.1397)
			(layers "B.Cu" "B.Mask" "B.Paste")
			(net "P3V3_DPB")
			(options
				(clearance outline)
				(anchor circle)
			)
			(primitives
				(gr_poly
					(pts
						(arc
							(start -0.1778 0.2794)
							(mid -0.249642 0.249642)
							(end -0.2794 0.1778)
						)
						(arc
							(start -0.2794 -0.1778)
							(mid -0.249642 -0.249642)
							(end -0.1778 -0.2794)
						)
						(arc
							(start 0.1778 -0.2794)
							(mid 0.249642 -0.249642)
							(end 0.2794 -0.1778)
						)
						(arc
							(start 0.2794 0.1778)
							(mid 0.249642 0.249642)
							(end 0.1778 0.2794)
						)
					)
					(width 0)
					(fill yes)
				)
			)
		)
		(pad "2" smd custom
			(at 0 0.4445 90)
			(size 0.1397 0.1397)
			(layers "B.Cu" "B.Mask" "B.Paste")
			(net "Z50_TEMP_1_ALERT#")
			(options
				(clearance outline)
				(anchor circle)
			)
			(primitives
				(gr_poly
					(pts
						(arc
							(start -0.1778 0.2794)
							(mid -0.249642 0.249642)
							(end -0.2794 0.1778)
						)
						(arc
							(start -0.2794 -0.1778)
							(mid -0.249642 -0.249642)
							(end -0.1778 -0.2794)
						)
						(arc
							(start 0.1778 -0.2794)
							(mid 0.249642 -0.249642)
							(end 0.2794 -0.1778)
						)
						(arc
							(start 0.2794 0.1778)
							(mid 0.249642 0.249642)
							(end 0.1778 0.2794)
						)
					)
					(width 0)
					(fill yes)
				)
			)
		)
	)
)
